FILE_TYPE = CONNECTIVITY;
{Allegro Design Entry HDL 16.6-p007 (v16-6-112F) 10/10/2012}
"PAGE_NUMBER" = 116;
0"NC";
1"SATA6G_PCH_PCIE_UP_SATA_TXP<7:0>";
2"SATA6G_PCH_PCIE_UP_SATA_TXN<7:0>";
3"SATA6G_PCH_PCIE_UP_SATA_RXP<7:0>";
4"SATA6G_PCH_PCIE_UP_SATA_RXN<7:0>";
5"GND\g";
6"GND\g";
7"GND\g";
8"A_EXTCLKP";
9"P2E_SSB_BMC_TX_C_DN";
10"SATA6G_S1_TX_DN";
11"SATA6G_S1_TX_DP";
12"P2E_SSB_BMC_TX_DN";
13"P3E_PCH_M2_TX_DP<3>";
14"SATA6G_PCH_PCIE_UP_SATA_RXP<6>";
15"SATA6G_PCH_PCIE_UP_SATA_RXP<1>";
16"SATA6G_PCH_PCIE_UP_SATA_RXN<1>";
17"SATA6G_PCH_PCIE_UP_SATA_RXP<4>";
18"SATA6G_PCH_PCIE_UP_SATA_RXP<2>";
19"SATA6G_PCH_PCIE_UP_SATA_RXN<2>";
20"SATA6G_PCH_PCIE_UP_SATA_RXP<0>";
21"SATA6G_PCH_PCIE_UP_SATA_RXN<0>";
22"SATA6G_S1_RX_DP";
23"SATA6G_S1_RX_DN";
24"SATA6G_PCH_PCIE_UP_SATA_RXN<3>";
25"SATA6G_PCH_PCIE_UP_SATA_RXP<3>";
26"SATA6G_PCH_PCIE_UP_SATA_RXN<4>";
27"SATA6G_PCH_PCIE_UP_SATA_RXN<5>";
28"SATA6G_PCH_PCIE_UP_SATA_RXP<5>";
29"SATA6G_PCH_PCIE_UP_SATA_RXN<6>";
30"SATA6G_PCH_PCIE_UP_SATA_TXN<2>";
31"SATA6G_PCH_PCIE_UP_SATA_TXP<2>";
32"SATA6G_PCH_PCIE_UP_SATA_TXP<1>";
33"SATA6G_PCH_PCIE_UP_SATA_TXN<1>";
34"SATA6G_PCH_PCIE_UP_SATA_TXN<0>";
35"SATA6G_PCH_PCIE_UP_SATA_TXP<0>";
36"SATA6G_PCH_PCIE_UP_SATA_TXN<3>";
37"SATA6G_S0_TX_DN";
38"PE_PCH_SPRV_TX_DP";
39"PE_PCH_SPRV_TX_DN";
40"SATA6G_S0_RX_DP";
41"SATA6G_S0_RX_DN";
42"PE_PCH_SPRV_RX_C_DP";
43"PE_PCH_SPRV_RX_C_DN";
44"P2E_SSB_BMC_RX_C_DP";
45"P2E_SSB_BMC_RX_C_DN";
46"A_PCIE_RCOMP_N";
47"A_PCIEUP_RCOMP_N";
48"A_PCIEUP_RCOMP_P";
49"TP_PCH_RSVD47";
50"TP_PCH_RSVD48";
51"P3E_PCH_RX_0_DN";
52"A_PCIE_RCOMP_P";
53"P2E_SSB_BMC_RX_C_DP";
54"P2E_SSB_BMC_RX_C_DN";
55"P2E_SSB_BMC_TX_C_DP";
56"TP_PCH_RSVD52";
57"SATA6G_PCH_PCIE_UP_SATA_RXN<7>";
58"P3E_PCH_M2_TX_DN<2>";
59"P3E_PCH_M2_RX_DP<2>";
60"P3E_PCH_M2_RX_DN<2>";
61"P3E_PCH_M2_TX_DP<1>";
62"P3E_PCH_M2_TX_DN<1>";
63"P3E_PCH_TX_0_DP";
64"P3E_PCH_RX_0_DP";
65"P3E_PCH_M2_TX_DN<3>";
66"P3E_PCH_M2_RX_DN<3>";
67"TP_PCH_RSVD49";
68"SATA6G_PCH_PCIE_UP_SATA_TXP<7>";
69"SATA6G_PCH_PCIE_UP_SATA_TXN<7>";
70"SATA6G_PCH_PCIE_UP_SATA_RXP<7>";
71"SATA6G_PCH_PCIE_UP_SATA_TXP<6>";
72"SATA6G_PCH_PCIE_UP_SATA_TXN<6>";
73"SATA6G_PCH_PCIE_UP_SATA_TXP<5>";
74"SATA6G_PCH_PCIE_UP_SATA_TXN<5>";
75"SATA6G_PCH_PCIE_UP_SATA_TXP<4>";
76"SATA6G_PCH_PCIE_UP_SATA_TXN<4>";
77"SATA6G_PCH_PCIE_UP_SATA_TXP<3>";
78"P3E_PCH_M2_RX_DN<1>";
79"P3E_PCH_M2_RX_DP<1>";
80"P3E_PCH_M2_RX_DP<3>";
81"SATA6G_S0_TX_DP";
82"P2E_SSB_BMC_TX_DP";
83"P3E_PCH_M2_TX_DP<2>";
84"TP_PCH_RSVD50";
85"TP_PCH_RSVD51";
86"A_EXTCLKN";
87"P3E_PCH_TX_0_DN";
%"RES"
"2","(-7550,2150)","2","mstr_discrete","I108";
;
CDS_SEC"1"
TOLERANCE"1%"
WATTAGE"1/16W"
MATERIAL"CHIP"
VALUE"100.0"
LOCATION"R3M11"
PART_NUMBER"G21796-017"
PACK_TYPE"0402"
SEC"1"
NO_XNET_CONNECTION"1"
ROOM"SB"
SEC_TYPE"0402"
CDS_LIB"mstr_discrete"
CDS_LOCATION"R3M11";
"A"
$PN"1"52;
"B"
$PN"2"46;
%"TAP"
"1","(-1875,3900)","0","mstr_standard","I122";
;
CDS_LIB"mstr_standard"
BODY_TYPE"PLUMBING"
HDL_TAP"TRUE";
"B \NAC \NWC"2;
"S \NAC"
BN"5"74;
%"TAP"
"1","(-1875,3800)","0","mstr_standard","I123";
;
CDS_LIB"mstr_standard"
BODY_TYPE"PLUMBING"
HDL_TAP"TRUE";
"B \NAC \NWC"2;
"S \NAC"
BN"4"76;
%"TAP"
"1","(-2025,4150)","0","mstr_standard","I125";
;
CDS_LIB"mstr_standard"
BODY_TYPE"PLUMBING"
HDL_TAP"TRUE";
"B \NAC \NWC"1;
"S \NAC"
BN"7"68;
%"TAP"
"1","(-2025,4050)","0","mstr_standard","I128";
;
CDS_LIB"mstr_standard"
BODY_TYPE"PLUMBING"
HDL_TAP"TRUE";
"B \NAC \NWC"1;
"S \NAC"
BN"6"71;
%"TAP"
"1","(-1875,4000)","0","mstr_standard","I129";
;
CDS_LIB"mstr_standard"
BODY_TYPE"PLUMBING"
HDL_TAP"TRUE";
"B \NAC \NWC"2;
"S \NAC"
BN"6"72;
%"TAP"
"1","(-1875,4100)","0","mstr_standard","I130";
;
CDS_LIB"mstr_standard"
BODY_TYPE"PLUMBING"
HDL_TAP"TRUE";
"B \NAC \NWC"2;
"S \NAC"
BN"7"69;
%"TAP"
"1","(-1875,3700)","0","mstr_standard","I131";
;
CDS_LIB"mstr_standard"
BODY_TYPE"PLUMBING"
HDL_TAP"TRUE";
"B \NAC \NWC"2;
"S \NAC"
BN"3"36;
%"TAP"
"1","(-1875,3600)","0","mstr_standard","I132";
;
CDS_LIB"mstr_standard"
BODY_TYPE"PLUMBING"
HDL_TAP"TRUE";
"B \NAC \NWC"2;
"S \NAC"
BN"2"30;
%"TAP"
"1","(-1875,3500)","0","mstr_standard","I133";
;
CDS_LIB"mstr_standard"
BODY_TYPE"PLUMBING"
HDL_TAP"TRUE";
"B \NAC \NWC"2;
"S \NAC"
BN"1"33;
%"TAP"
"1","(-1875,3400)","0","mstr_standard","I134";
;
CDS_LIB"mstr_standard"
BODY_TYPE"PLUMBING"
HDL_TAP"TRUE";
"B \NAC \NWC"2;
"S \NAC"
BN"0"34;
%"TAP"
"1","(-2025,3950)","0","mstr_standard","I135";
;
CDS_LIB"mstr_standard"
BODY_TYPE"PLUMBING"
HDL_TAP"TRUE";
"B \NAC \NWC"1;
"S \NAC"
BN"5"73;
%"TAP"
"1","(-2025,3850)","0","mstr_standard","I136";
;
CDS_LIB"mstr_standard"
BODY_TYPE"PLUMBING"
HDL_TAP"TRUE";
"B \NAC \NWC"1;
"S \NAC"
BN"4"75;
%"TAP"
"1","(-2025,3750)","0","mstr_standard","I137";
;
CDS_LIB"mstr_standard"
BODY_TYPE"PLUMBING"
HDL_TAP"TRUE";
"B \NAC \NWC"1;
"S \NAC"
BN"3"77;
%"TAP"
"1","(-2025,3650)","0","mstr_standard","I138";
;
CDS_LIB"mstr_standard"
BODY_TYPE"PLUMBING"
HDL_TAP"TRUE";
"B \NAC \NWC"1;
"S \NAC"
BN"2"31;
%"TAP"
"1","(-2025,3550)","0","mstr_standard","I139";
;
CDS_LIB"mstr_standard"
BODY_TYPE"PLUMBING"
HDL_TAP"TRUE";
"B \NAC \NWC"1;
"S \NAC"
BN"1"32;
%"TAP"
"1","(-2025,3450)","0","mstr_standard","I140";
;
CDS_LIB"mstr_standard"
BODY_TYPE"PLUMBING"
HDL_TAP"TRUE";
"B \NAC \NWC"1;
"S \NAC"
BN"0"35;
%"TAP"
"1","(-6400,3450)","2","mstr_standard","I141";
;
CDS_LIB"mstr_standard"
BODY_TYPE"PLUMBING"
HDL_TAP"TRUE";
"B \NAC \NWC"3;
"S \NAC"
BN"0"20;
%"TAP"
"1","(-6250,3400)","2","mstr_standard","I142";
;
CDS_LIB"mstr_standard"
BODY_TYPE"PLUMBING"
HDL_TAP"TRUE";
"B \NAC \NWC"4;
"S \NAC"
BN"0"21;
%"TAP"
"1","(-6250,3500)","2","mstr_standard","I143";
;
CDS_LIB"mstr_standard"
BODY_TYPE"PLUMBING"
HDL_TAP"TRUE";
"B \NAC \NWC"4;
"S \NAC"
BN"1"16;
%"TAP"
"1","(-6400,3650)","2","mstr_standard","I144";
;
CDS_LIB"mstr_standard"
BODY_TYPE"PLUMBING"
HDL_TAP"TRUE";
"B \NAC \NWC"3;
"S \NAC"
BN"2"18;
%"TAP"
"1","(-6400,3750)","2","mstr_standard","I145";
;
CDS_LIB"mstr_standard"
BODY_TYPE"PLUMBING"
HDL_TAP"TRUE";
"B \NAC \NWC"3;
"S \NAC"
BN"3"25;
%"TAP"
"1","(-6400,3550)","2","mstr_standard","I146";
;
CDS_LIB"mstr_standard"
BODY_TYPE"PLUMBING"
HDL_TAP"TRUE";
"B \NAC \NWC"3;
"S \NAC"
BN"1"15;
%"TAP"
"1","(-6250,3600)","2","mstr_standard","I147";
;
CDS_LIB"mstr_standard"
BODY_TYPE"PLUMBING"
HDL_TAP"TRUE";
"B \NAC \NWC"4;
"S \NAC"
BN"2"19;
%"TAP"
"1","(-6250,3700)","2","mstr_standard","I148";
;
CDS_LIB"mstr_standard"
BODY_TYPE"PLUMBING"
HDL_TAP"TRUE";
"B \NAC \NWC"4;
"S \NAC"
BN"3"24;
%"TAP"
"1","(-6400,3850)","2","mstr_standard","I149";
;
CDS_LIB"mstr_standard"
BODY_TYPE"PLUMBING"
HDL_TAP"TRUE";
"B \NAC \NWC"3;
"S \NAC"
BN"4"17;
%"TAP"
"1","(-6400,3950)","2","mstr_standard","I150";
;
CDS_LIB"mstr_standard"
BODY_TYPE"PLUMBING"
HDL_TAP"TRUE";
"B \NAC \NWC"3;
"S \NAC"
BN"5"28;
%"TAP"
"1","(-6250,4000)","2","mstr_standard","I151";
;
CDS_LIB"mstr_standard"
BODY_TYPE"PLUMBING"
HDL_TAP"TRUE";
"B \NAC \NWC"4;
"S \NAC"
BN"6"29;
%"TAP"
"1","(-6250,3900)","2","mstr_standard","I152";
;
CDS_LIB"mstr_standard"
BODY_TYPE"PLUMBING"
HDL_TAP"TRUE";
"B \NAC \NWC"4;
"S \NAC"
BN"5"27;
%"TAP"
"1","(-6250,3800)","2","mstr_standard","I153";
;
CDS_LIB"mstr_standard"
BODY_TYPE"PLUMBING"
HDL_TAP"TRUE";
"B \NAC \NWC"4;
"S \NAC"
BN"4"26;
%"TAP"
"1","(-6400,4150)","2","mstr_standard","I154";
;
CDS_LIB"mstr_standard"
BODY_TYPE"PLUMBING"
HDL_TAP"TRUE";
"B \NAC \NWC"3;
"S \NAC"
BN"7"70;
%"TAP"
"1","(-6400,4050)","2","mstr_standard","I155";
;
CDS_LIB"mstr_standard"
BODY_TYPE"PLUMBING"
HDL_TAP"TRUE";
"B \NAC \NWC"3;
"S \NAC"
BN"6"14;
%"TAP"
"1","(-6250,4100)","2","mstr_standard","I156";
;
CDS_LIB"mstr_standard"
BODY_TYPE"PLUMBING"
HDL_TAP"TRUE";
"B \NAC \NWC"4;
"S \NAC"
BN"7"57;
%"RES"
"2","(-7125,2150)","2","mstr_discrete","I181";
;
CDS_SEC"1"
PACK_TYPE"0402"
WATTAGE"1/16W"
LOCATION"R3M12"
MATERIAL"CHIP"
TOLERANCE"1%"
VALUE"100.0"
PART_NUMBER"G21796-017"
CDS_LIB"mstr_discrete"
SEC"1"
CDS_LOCATION"R3M12"
NO_XNET_CONNECTION"1"
ROOM"SB"
SEC_TYPE"0402";
"A"
$PN"1"48;
"B"
$PN"2"47;
%"LBG_CORE_QAT_EXT_D"
"3","(-4025,2850)","0","mstr_u_proc","I220";
;
CDS_SEC"3"
PART_NUMBER"H91415-002"
LOCATION"U7C1"
MATERIAL"IC"
SEC_TYPE"BGA1"
SEC"3"
BOM_COST"SB"
CDS_LOCATION"U7C1"
ROOM"SB"
PACK_TYPE"BGA1"
CDS_LIB"mstr_u_proc";
"USB3_9_PCIE2_TXP"
$PN"BL66"83;
"USB3_9_PCIE2_TXN"
$PN"BK65"58;
"USB3_9_PCIE2_RXP"
$PN"AW69"59;
"USB3_9_PCIE2_RXN"
$PN"AW71"60;
"USB3_8_PCIE1_TXP"
$PN"BR65"61;
"USB3_8_PCIE1_TXN"
$PN"BM65"62;
"USB3_8_PCIE1_RXP"
$PN"AY70"79;
"USB3_8_PCIE1_RXN"
$PN"AY72"78;
"USB3_7_PCIE0_TXP"
$PN"BN63"63;
"USB3_7_PCIE0_TXN"
$PN"BR61"87;
"USB3_7_PCIE0_RXP"
$PN"BA69"64;
"USB3_7_PCIE0_RXN"
$PN"BA71"51;
"USB3_10_PCIE3_GBE_TXP"
$PN"BK61"13;
"USB3_10_PCIE3_GBE_TXN"
$PN"BH61"65;
"USB3_10_PCIE3_GBE_RXP"
$PN"AV70"80;
"USB3_10_PCIE3_GBE_RXN"
$PN"AV72"66;
"RSVD<47>"
$PN"AP69"49;
"RSVD<48>"
$PN"AP71"50;
"RSVD<49>"
$PN"G67"67;
"RSVD<50>"
$PN"H69"84;
"RSVD<51>"
$PN"AA69"85;
"RSVD<52>"
$PN"AA71"56;
"PCIE_RCOMPP"
$PN"BB56"52;
"PCIE_RCOMPN"
$PN"BD58"46;
"PCIEUP_RCOMPP"
$PN"AH58"48;
"PCIEUP_RCOMPN"
$PN"AF58"47;
"PCIE9_SSATA3_TXP"
$PN"AE71"0;
"PCIE9_SSATA3_TXN"
$PN"AE69"0;
"PCIE9_SSATA3_RXP"
$PN"AY66"0;
"PCIE9_SSATA3_RXN"
$PN"AW65"0;
"PCIE8_SSATA2_GBE_TXP"
$PN"AF72"0;
"PCIE8_SSATA2_GBE_TXN"
$PN"AF70"0;
"PCIE8_SSATA2_GBE_RXP"
$PN"BD65"0;
"PCIE8_SSATA2_GBE_RXN"
$PN"BA65"0;
"PCIE7_SSATA1_TXP"
$PN"AH71"11;
"PCIE7_SSATA1_TXN"
$PN"AH69"10;
"PCIE7_SSATA1_RXP"
$PN"BA61"22;
"PCIE7_SSATA1_RXN"
$PN"AY59"23;
"PCIE6_SSATA0_TXP"
$PN"AJ72"81;
"PCIE6_SSATA0_TXN"
$PN"AJ70"37;
"PCIE6_SSATA0_RXP"
$PN"BD61"40;
"PCIE6_SSATA0_RXN"
$PN"BB63"41;
"PCIE5_GBE_TXP"
$PN"BJ63"38;
"PCIE5_GBE_TXN"
$PN"BH65"39;
"PCIE5_GBE_RXP"
$PN"AM71"42;
"PCIE5_GBE_RXN"
$PN"AM69"43;
"PCIE4_GBE_TXP"
$PN"BJ66"82;
"PCIE4_GBE_TXN"
$PN"BG66"12;
"PCIE4_GBE_RXP"
$PN"AN72"44;
"PCIE4_GBE_RXN"
$PN"AN70"45;
"PCIE19_UP7_SATA7_TXP"
$PN"L72"68;
"PCIE19_UP7_SATA7_TXN"
$PN"L70"69;
"PCIE19_UP7_SATA7_RXP"
$PN"AD61"70;
"PCIE19_UP7_SATA7_RXN"
$PN"AA61"57;
"PCIE18_UP6_SATA6_TXP"
$PN"M71"71;
"PCIE18_UP6_SATA6_TXN"
$PN"M69"72;
"PCIE18_UP6_SATA6_RXP"
$PN"AN61"14;
"PCIE18_UP6_SATA6_RXN"
$PN"AP59"29;
"PCIE17_UP5_SATA5_TXP"
$PN"N72"73;
"PCIE17_UP5_SATA5_TXN"
$PN"N70"74;
"PCIE17_UP5_SATA5_RXP"
$PN"AG63"28;
"PCIE17_UP5_SATA5_RXN"
$PN"AH61"27;
"PCIE16_UP4_SATA4_TXP"
$PN"P71"75;
"PCIE16_UP4_SATA4_TXN"
$PN"P69"76;
"PCIE16_UP4_SATA4_RXP"
$PN"AH65"17;
"PCIE16_UP4_SATA4_RXN"
$PN"AF65"26;
"PCIE15_UP3_SATA3_TXP"
$PN"R72"77;
"PCIE15_UP3_SATA3_TXN"
$PN"R70"36;
"PCIE15_UP3_SATA3_RXP"
$PN"AL63"25;
"PCIE15_UP3_SATA3_RXN"
$PN"AP63"24;
"PCIE14_UP2_SATA2_TXP"
$PN"T71"31;
"PCIE14_UP2_SATA2_TXN"
$PN"T69"30;
"PCIE14_UP2_SATA2_RXP"
$PN"AJ63"18;
"PCIE14_UP2_SATA2_RXN"
$PN"AK65"19;
"PCIE13_UP1_SATA1_TXP"
$PN"V72"32;
"PCIE13_UP1_SATA1_TXN"
$PN"V70"33;
"PCIE13_UP1_SATA1_RXP"
$PN"AN65"15;
"PCIE13_UP1_SATA1_RXN"
$PN"AL66"16;
"PCIE12_UP0_SATA0_TXP"
$PN"W71"35;
"PCIE12_UP0_SATA0_TXN"
$PN"W69"34;
"PCIE12_UP0_SATA0_RXP"
$PN"AT63"20;
"PCIE12_UP0_SATA0_RXN"
$PN"AR61"21;
"PCIE11_SSATA5_GBE_TXP"
$PN"AC71"0;
"PCIE11_SSATA5_GBE_TXN"
$PN"AC69"0;
"PCIE11_SSATA5_GBE_RXP"
$PN"AV66"0;
"PCIE11_SSATA5_GBE_RXN"
$PN"AT66"0;
"PCIE10_SSATA4_TXP"
$PN"AD72"0;
"PCIE10_SSATA4_TXN"
$PN"AD70"0;
"PCIE10_SSATA4_RXP"
$PN"AU65"0;
"PCIE10_SSATA4_RXN"
$PN"AV63"0;
"EXTCLKP"
$PN"E67"8;
"EXTCLKN"
$PN"D66"86;
%"RES"
"2","(-2125,1400)","0","mstr_discrete","I229";
;
CDS_SEC"1"
PART_NUMBER"G21796-016"
PACK_TYPE"0402"
MATERIAL"EMPTY"
WATTAGE"1/16W"
VALUE"10.0K"
LOCATION"R7B8"
TOLERANCE"1%"
ROOM"SB"
SEC"1"
SEC_TYPE"0402"
CDS_LOCATION"R7B8"
CDS_LIB"mstr_discrete";
"A"
$PN"1"86;
"B"
$PN"2"5;
%"RES"
"2","(-1825,1400)","0","mstr_discrete","I230";
;
CDS_SEC"1"
WATTAGE"1/16W"
MATERIAL"EMPTY"
PART_NUMBER"G21796-016"
VALUE"10.0K"
LOCATION"R7B7"
TOLERANCE"1%"
PACK_TYPE"0402"
SEC_TYPE"0402"
SEC"1"
ROOM"SB"
CDS_LOCATION"R7B7"
CDS_LIB"mstr_discrete";
"A"
$PN"1"8;
"B"
$PN"2"5;
%"GND"
"1","(-1925,1000)","0","mstr_symbols","I231";
;
CDS_LIB"mstr_symbols"
SIZE"1B"
VOLTAGE"0.0V"
BODY_TYPE"PLUMBING"
HDL_POWER"GND";
"A\NAC"5;
%"RES"
"2","(-6250,750)","0","mstr_discrete","I234";
;
POP"NOPOP"
PART_NUMBER"G21796-010"
PACK_TYPE"0402"
TOLERANCE"1%"
WATTAGE"1/16W"
MATERIAL"CHIP"
LOCATION"R3M9"
VALUE"100.0K"
CDS_LIB"mstr_discrete"
ROOM"SB"
CDS_SEC"1"
$SEC"1"
CDS_LOCATION"R3M9";
"A"
$PN"1"54;
"B"
$PN"2"6;
%"RES"
"2","(-5900,750)","0","mstr_discrete","I235";
;
POP"NOPOP"
PACK_TYPE"0402"
PART_NUMBER"G21796-010"
MATERIAL"CHIP"
VALUE"100.0K"
WATTAGE"1/16W"
TOLERANCE"1%"
LOCATION"R3M8"
CDS_LIB"mstr_discrete"
CDS_LOCATION"R3M8"
$SEC"1"
ROOM"SB"
CDS_SEC"1";
"A"
$PN"1"53;
"B"
$PN"2"7;
%"GND"
"1","(-6250,475)","0","mstr_symbols","I236";
;
VOLTAGE"0.0V"
CDS_LIB"mstr_symbols"
SIZE"1B"
BODY_TYPE"PLUMBING"
HDL_POWER"GND";
"A\NAC"6;
%"GND"
"1","(-5900,475)","0","mstr_symbols","I237";
;
VOLTAGE"0.0V"
CDS_LIB"mstr_symbols"
SIZE"1B"
BODY_TYPE"PLUMBING"
HDL_POWER"GND";
"A\NAC"7;
%"CAP_A"
"1","(-1725,2650)","1","dev_discrete","I238";
;
PACK_TYPE"0402V"
MATERIAL"X7R"
VOLTAGE"16V"
PART_NUMBER"A36096-030"
VALUE"0.1UF"
TOLERANCE"10%"
LOCATION"C2M4"
GROUP"AST2500"
CDS_LOCATION"C2M4"
SEC"1"
SEC_TYPE"0402V"
CDS_SEC"1"
CDS_LIB"dev_discrete"
BOM_COST"PROC_SIDEBAND"
ROOM"PROC_SIDEBAND";
"B"
$PN"2"55;
"A"
$PN"1"82;
%"CAP_A"
"1","(-1325,2600)","1","dev_discrete","I239";
;
VALUE"0.1UF"
LOCATION"C2M3"
PART_NUMBER"A36096-030"
VOLTAGE"16V"
MATERIAL"X7R"
PACK_TYPE"0402V"
TOLERANCE"10%"
GROUP"AST2500"
CDS_LOCATION"C2M3"
SEC"1"
SEC_TYPE"0402V"
CDS_SEC"1"
CDS_LIB"dev_discrete"
BOM_COST"PROC_SIDEBAND"
ROOM"PROC_SIDEBAND";
"B"
$PN"2"9;
"A"
$PN"1"12;
END.
